(kicad_pcb
	(version 20260206)
	(generator "pcbnew")
	(generator_version "10.0")
	(general
		(thickness 1.6)
		(legacy_teardrops no)
	)
	(paper "A4")
	(title_block
		(title "04192023_DAF0TMB3IC0_F0TG_MB_C_brd_V02_OCP.brd")
		(comment 1 "Grand Teton / footprints 2437-2442 of 8354")
	)
	(layers
		(0 "F.Cu" signal "TOP")
		(4 "In1.Cu" signal "GND")
		(6 "In2.Cu" signal "IN1")
		(8 "In3.Cu" signal "GND1")
		(10 "In4.Cu" signal "IN2")
		(12 "In5.Cu" signal "GND2")
		(14 "In6.Cu" signal "IN3")
		(16 "In7.Cu" signal "GND3")
		(18 "In8.Cu" signal "VCC")
		(20 "In9.Cu" signal "VCC1")
		(22 "In10.Cu" signal "GND4")
		(24 "In11.Cu" signal "IN4")
		(26 "In12.Cu" signal "GND5")
		(28 "In13.Cu" signal "IN5")
		(30 "In14.Cu" signal "GND6")
		(32 "In15.Cu" signal "IN6")
		(34 "In16.Cu" signal "GND7")
		(2 "B.Cu" signal "BOTTOM")
		(9 "F.Adhes" user "F.Adhesive")
		(11 "B.Adhes" user "B.Adhesive")
		(13 "F.Paste" user "Package Geometry/Pastemask Top")
		(15 "B.Paste" user "Package Geometry/Pastemask Bottom")
		(5 "F.SilkS" user "Ref Des/Silkscreen Top")
		(7 "B.SilkS" user "Ref Des/Silkscreen Bottom")
		(1 "F.Mask" user "Board Geometry/Soldermask Top")
		(3 "B.Mask" user "Board Geometry/Soldermask Bottom")
		(17 "Dwgs.User" user "User.Drawings")
		(19 "Cmts.User" user "User.Comments")
		(21 "Eco1.User" user "User.Eco1")
		(23 "Eco2.User" user "User.Eco2")
		(25 "Edge.Cuts" user "Board Geometry/Outline")
		(27 "Margin" user)
		(31 "F.CrtYd" user "Package Geometry/Place Bound Top")
		(29 "B.CrtYd" user "Package Geometry/Place Bound Bottom")
		(35 "F.Fab" user "Ref Des/Assembly Top")
		(33 "B.Fab" user "Ref Des/Assembly Bottom")
	)
	(footprint ""
		(layer "F.Cu")
		(at 60.920122 -181.291992 -90)
		(property "Reference" "PC278"
			(at 0 0 270)
			(layer "F.SilkS")
			(hide yes)
			(effects
				(font
					(size 1.27 1.27)
				)
			)
		)
		(property "Value" ""
			(at 0 0 270)
			(layer "F.Fab")
			(effects
				(font
					(size 1.27 1.27)
				)
			)
		)
		(duplicate_pad_numbers_are_jumpers no)
		(fp_line
			(start -0.7874 0.4064)
			(end -0.7874 -0.4064)
			(stroke
				(width 0.1524)
				(type default)
			)
			(layer "F.SilkS")
		)
		(fp_line
			(start 0.7874 0.4064)
			(end -0.7874 0.4064)
			(stroke
				(width 0.1524)
				(type default)
			)
			(layer "F.SilkS")
		)
		(fp_line
			(start -0.7874 -0.4064)
			(end 0.7874 -0.4064)
			(stroke
				(width 0.1524)
				(type default)
			)
			(layer "F.SilkS")
		)
		(fp_line
			(start 0.7874 -0.4064)
			(end 0.7874 0.4064)
			(stroke
				(width 0.1524)
				(type default)
			)
			(layer "F.SilkS")
		)
		(fp_line
			(start -0.67945 0.3048)
			(end -0.67945 -0.305054)
			(stroke
				(width 0.1)
				(type default)
			)
			(layer "F.Fab")
		)
		(fp_line
			(start -0.12065 0.3048)
			(end -0.67945 0.3048)
			(stroke
				(width 0.1)
				(type default)
			)
			(layer "F.Fab")
		)
		(fp_line
			(start 0.120396 0.3048)
			(end 0.120396 0.2794)
			(stroke
				(width 0.1)
				(type default)
			)
			(layer "F.Fab")
		)
		(fp_line
			(start 0.67945 0.3048)
			(end 0.120396 0.3048)
			(stroke
				(width 0.1)
				(type default)
			)
			(layer "F.Fab")
		)
		(fp_line
			(start -0.12065 0.2794)
			(end -0.12065 0.3048)
			(stroke
				(width 0.1)
				(type default)
			)
			(layer "F.Fab")
		)
		(fp_line
			(start 0.120396 0.2794)
			(end -0.12065 0.2794)
			(stroke
				(width 0.1)
				(type default)
			)
			(layer "F.Fab")
		)
		(fp_line
			(start -0.12065 -0.2794)
			(end 0.12065 -0.2794)
			(stroke
				(width 0.1)
				(type default)
			)
			(layer "F.Fab")
		)
		(fp_line
			(start 0.12065 -0.2794)
			(end 0.12065 -0.3048)
			(stroke
				(width 0.1)
				(type default)
			)
			(layer "F.Fab")
		)
		(fp_line
			(start 0.12065 -0.3048)
			(end 0.67945 -0.3048)
			(stroke
				(width 0.1)
				(type default)
			)
			(layer "F.Fab")
		)
		(fp_line
			(start 0.67945 -0.3048)
			(end 0.67945 0.3048)
			(stroke
				(width 0.1)
				(type default)
			)
			(layer "F.Fab")
		)
		(fp_line
			(start -0.67945 -0.305054)
			(end -0.12065 -0.305054)
			(stroke
				(width 0.1)
				(type default)
			)
			(layer "F.Fab")
		)
		(fp_line
			(start -0.12065 -0.305054)
			(end -0.12065 -0.2794)
			(stroke
				(width 0.1)
				(type default)
			)
			(layer "F.Fab")
		)
		(pad "1" smd circle
			(at -0.40005 0 270)
			(size 0 0)
			(layers "F.Cu" "F.Mask" "F.Paste")
			(net "PVDDCR_CPU0_P1")
		)
		(pad "2" smd circle
			(at 0.40005 0 270)
			(size 0 0)
			(layers "F.Cu" "F.Mask" "F.Paste")
			(net "GND")
		)
	)
	(footprint ""
		(layer "F.Cu")
		(at 140.208 -111.633 -90)
		(property "Reference" "U8009"
			(at 1.7018 -2.253488 90)
			(unlocked yes)
			(layer "F.SilkS")
			(effects
				(font
					(size 0.7874 0.5842)
					(thickness 0.1524)
				)
				(justify left)
			)
		)
		(property "Value" ""
			(at 0 0 270)
			(layer "F.Fab")
			(effects
				(font
					(size 1.27 1.27)
				)
			)
		)
		(duplicate_pad_numbers_are_jumpers no)
		(fp_line
			(start -1.868424 1.519936)
			(end 1.868424 1.519936)
			(stroke
				(width 0.1524)
				(type default)
			)
			(layer "F.SilkS")
		)
		(fp_line
			(start 1.868424 1.519936)
			(end 1.868424 -1.519936)
			(stroke
				(width 0.1524)
				(type default)
			)
			(layer "F.SilkS")
		)
		(fp_line
			(start -1.868424 -1.519936)
			(end -1.868424 1.519936)
			(stroke
				(width 0.1524)
				(type default)
			)
			(layer "F.SilkS")
		)
		(fp_line
			(start 1.868424 -1.519936)
			(end -1.868424 -1.519936)
			(stroke
				(width 0.1524)
				(type default)
			)
			(layer "F.SilkS")
		)
		(fp_line
			(start -0.700024 1.519936)
			(end 0.700024 1.519936)
			(stroke
				(width 0.1)
				(type default)
			)
			(layer "F.Fab")
		)
		(fp_line
			(start 0.700024 1.519936)
			(end 0.700024 -1.519936)
			(stroke
				(width 0.1)
				(type default)
			)
			(layer "F.Fab")
		)
		(fp_line
			(start -0.700024 -1.519936)
			(end -0.700024 1.519936)
			(stroke
				(width 0.1)
				(type default)
			)
			(layer "F.Fab")
		)
		(fp_line
			(start 0.700024 -1.519936)
			(end -0.700024 -1.519936)
			(stroke
				(width 0.1)
				(type default)
			)
			(layer "F.Fab")
		)
		(pad "1" smd rect
			(at -1.18491 -0.94996 180)
			(size 0.6096 1.0668)
			(layers "F.Cu" "F.Mask" "F.Paste")
			(net "UV_P2V5_COMP")
		)
		(pad "2" smd rect
			(at -1.18491 0.94996 180)
			(size 0.6096 1.0668)
			(layers "F.Cu" "F.Mask" "F.Paste")
			(net "GND")
		)
		(pad "3" smd rect
			(at 1.18491 0 180)
			(size 0.6096 1.0668)
			(layers "F.Cu" "F.Mask" "F.Paste")
			(net "Net_10849")
		)
	)
	(footprint ""
		(layer "F.Cu")
		(at 321.107308 -103.40975)
		(property "Reference" "R1308"
			(at 0 0 0)
			(layer "F.SilkS")
			(hide yes)
			(effects
				(font
					(size 1.27 1.27)
				)
			)
		)
		(property "Value" ""
			(at 0 0 0)
			(layer "F.Fab")
			(effects
				(font
					(size 1.27 1.27)
				)
			)
		)
		(duplicate_pad_numbers_are_jumpers no)
		(fp_line
			(start -0.7874 -0.4064)
			(end 0.7874 -0.4064)
			(stroke
				(width 0.1524)
				(type default)
			)
			(layer "F.SilkS")
		)
		(fp_line
			(start -0.7874 0.4064)
			(end -0.7874 -0.4064)
			(stroke
				(width 0.1524)
				(type default)
			)
			(layer "F.SilkS")
		)
		(fp_line
			(start 0.7874 -0.4064)
			(end 0.7874 0.4064)
			(stroke
				(width 0.1524)
				(type default)
			)
			(layer "F.SilkS")
		)
		(fp_line
			(start 0.7874 0.4064)
			(end -0.7874 0.4064)
			(stroke
				(width 0.1524)
				(type default)
			)
			(layer "F.SilkS")
		)
		(fp_line
			(start -0.67945 -0.305054)
			(end -0.12065 -0.305054)
			(stroke
				(width 0.1)
				(type default)
			)
			(layer "F.Fab")
		)
		(fp_line
			(start -0.67945 0.3048)
			(end -0.67945 -0.305054)
			(stroke
				(width 0.1)
				(type default)
			)
			(layer "F.Fab")
		)
		(fp_line
			(start -0.12065 -0.305054)
			(end -0.12065 -0.2794)
			(stroke
				(width 0.1)
				(type default)
			)
			(layer "F.Fab")
		)
		(fp_line
			(start -0.12065 -0.2794)
			(end 0.12065 -0.2794)
			(stroke
				(width 0.1)
				(type default)
			)
			(layer "F.Fab")
		)
		(fp_line
			(start -0.12065 0.2794)
			(end -0.12065 0.3048)
			(stroke
				(width 0.1)
				(type default)
			)
			(layer "F.Fab")
		)
		(fp_line
			(start -0.12065 0.3048)
			(end -0.67945 0.3048)
			(stroke
				(width 0.1)
				(type default)
			)
			(layer "F.Fab")
		)
		(fp_line
			(start 0.120396 0.2794)
			(end -0.12065 0.2794)
			(stroke
				(width 0.1)
				(type default)
			)
			(layer "F.Fab")
		)
		(fp_line
			(start 0.120396 0.3048)
			(end 0.120396 0.2794)
			(stroke
				(width 0.1)
				(type default)
			)
			(layer "F.Fab")
		)
		(fp_line
			(start 0.12065 -0.3048)
			(end 0.67945 -0.3048)
			(stroke
				(width 0.1)
				(type default)
			)
			(layer "F.Fab")
		)
		(fp_line
			(start 0.12065 -0.2794)
			(end 0.12065 -0.3048)
			(stroke
				(width 0.1)
				(type default)
			)
			(layer "F.Fab")
		)
		(fp_line
			(start 0.67945 -0.3048)
			(end 0.67945 0.3048)
			(stroke
				(width 0.1)
				(type default)
			)
			(layer "F.Fab")
		)
		(fp_line
			(start 0.67945 0.3048)
			(end 0.120396 0.3048)
			(stroke
				(width 0.1)
				(type default)
			)
			(layer "F.Fab")
		)
		(pad "1" smd circle
			(at -0.40005 0)
			(size 0 0)
			(layers "F.Cu" "F.Mask" "F.Paste")
			(net "GND")
		)
		(pad "2" smd circle
			(at 0.40005 0)
			(size 0 0)
			(layers "F.Cu" "F.Mask" "F.Paste")
			(net "INA230_8_A0")
		)
	)
	(footprint ""
		(layer "F.Cu")
		(at 430.155858 -430.891188)
		(property "Reference" "C6087"
			(at 0 0 0)
			(layer "F.SilkS")
			(hide yes)
			(effects
				(font
					(size 1.27 1.27)
				)
			)
		)
		(property "Value" ""
			(at 0 0 0)
			(layer "F.Fab")
			(effects
				(font
					(size 1.27 1.27)
				)
			)
		)
		(duplicate_pad_numbers_are_jumpers no)
		(fp_line
			(start -0.7874 -0.4064)
			(end 0.7874 -0.4064)
			(stroke
				(width 0.1524)
				(type default)
			)
			(layer "F.SilkS")
		)
		(fp_line
			(start -0.7874 0.4064)
			(end -0.7874 -0.4064)
			(stroke
				(width 0.1524)
				(type default)
			)
			(layer "F.SilkS")
		)
		(fp_line
			(start 0.7874 -0.4064)
			(end 0.7874 0.4064)
			(stroke
				(width 0.1524)
				(type default)
			)
			(layer "F.SilkS")
		)
		(fp_line
			(start 0.7874 0.4064)
			(end -0.7874 0.4064)
			(stroke
				(width 0.1524)
				(type default)
			)
			(layer "F.SilkS")
		)
		(fp_line
			(start -0.67945 -0.305054)
			(end -0.12065 -0.305054)
			(stroke
				(width 0.1)
				(type default)
			)
			(layer "F.Fab")
		)
		(fp_line
			(start -0.67945 0.3048)
			(end -0.67945 -0.305054)
			(stroke
				(width 0.1)
				(type default)
			)
			(layer "F.Fab")
		)
		(fp_line
			(start -0.12065 -0.305054)
			(end -0.12065 -0.2794)
			(stroke
				(width 0.1)
				(type default)
			)
			(layer "F.Fab")
		)
		(fp_line
			(start -0.12065 -0.2794)
			(end 0.12065 -0.2794)
			(stroke
				(width 0.1)
				(type default)
			)
			(layer "F.Fab")
		)
		(fp_line
			(start -0.12065 0.2794)
			(end -0.12065 0.3048)
			(stroke
				(width 0.1)
				(type default)
			)
			(layer "F.Fab")
		)
		(fp_line
			(start -0.12065 0.3048)
			(end -0.67945 0.3048)
			(stroke
				(width 0.1)
				(type default)
			)
			(layer "F.Fab")
		)
		(fp_line
			(start 0.120396 0.2794)
			(end -0.12065 0.2794)
			(stroke
				(width 0.1)
				(type default)
			)
			(layer "F.Fab")
		)
		(fp_line
			(start 0.120396 0.3048)
			(end 0.120396 0.2794)
			(stroke
				(width 0.1)
				(type default)
			)
			(layer "F.Fab")
		)
		(fp_line
			(start 0.12065 -0.3048)
			(end 0.67945 -0.3048)
			(stroke
				(width 0.1)
				(type default)
			)
			(layer "F.Fab")
		)
		(fp_line
			(start 0.12065 -0.2794)
			(end 0.12065 -0.3048)
			(stroke
				(width 0.1)
				(type default)
			)
			(layer "F.Fab")
		)
		(fp_line
			(start 0.67945 -0.3048)
			(end 0.67945 0.3048)
			(stroke
				(width 0.1)
				(type default)
			)
			(layer "F.Fab")
		)
		(fp_line
			(start 0.67945 0.3048)
			(end 0.120396 0.3048)
			(stroke
				(width 0.1)
				(type default)
			)
			(layer "F.Fab")
		)
		(pad "1" smd circle
			(at -0.40005 0)
			(size 0 0)
			(layers "F.Cu" "F.Mask" "F.Paste")
			(net "P3V3_AUX")
		)
		(pad "2" smd circle
			(at 0.40005 0)
			(size 0 0)
			(layers "F.Cu" "F.Mask" "F.Paste")
			(net "GND")
		)
	)
	(footprint ""
		(layer "F.Cu")
		(at 187.316618 -427.255178 -90)
		(property "Reference" "R3499"
			(at 0 0 270)
			(layer "F.SilkS")
			(hide yes)
			(effects
				(font
					(size 1.27 1.27)
				)
			)
		)
		(property "Value" ""
			(at 0 0 270)
			(layer "F.Fab")
			(effects
				(font
					(size 1.27 1.27)
				)
			)
		)
		(duplicate_pad_numbers_are_jumpers no)
		(fp_line
			(start -0.7874 0.4064)
			(end -0.7874 -0.4064)
			(stroke
				(width 0.1524)
				(type default)
			)
			(layer "F.SilkS")
		)
		(fp_line
			(start 0.7874 0.4064)
			(end -0.7874 0.4064)
			(stroke
				(width 0.1524)
				(type default)
			)
			(layer "F.SilkS")
		)
		(fp_line
			(start -0.7874 -0.4064)
			(end 0.7874 -0.4064)
			(stroke
				(width 0.1524)
				(type default)
			)
			(layer "F.SilkS")
		)
		(fp_line
			(start 0.7874 -0.4064)
			(end 0.7874 0.4064)
			(stroke
				(width 0.1524)
				(type default)
			)
			(layer "F.SilkS")
		)
		(fp_line
			(start -0.67945 0.3048)
			(end -0.67945 -0.305054)
			(stroke
				(width 0.1)
				(type default)
			)
			(layer "F.Fab")
		)
		(fp_line
			(start -0.12065 0.3048)
			(end -0.67945 0.3048)
			(stroke
				(width 0.1)
				(type default)
			)
			(layer "F.Fab")
		)
		(fp_line
			(start 0.120396 0.3048)
			(end 0.120396 0.2794)
			(stroke
				(width 0.1)
				(type default)
			)
			(layer "F.Fab")
		)
		(fp_line
			(start 0.67945 0.3048)
			(end 0.120396 0.3048)
			(stroke
				(width 0.1)
				(type default)
			)
			(layer "F.Fab")
		)
		(fp_line
			(start -0.12065 0.2794)
			(end -0.12065 0.3048)
			(stroke
				(width 0.1)
				(type default)
			)
			(layer "F.Fab")
		)
		(fp_line
			(start 0.120396 0.2794)
			(end -0.12065 0.2794)
			(stroke
				(width 0.1)
				(type default)
			)
			(layer "F.Fab")
		)
		(fp_line
			(start -0.12065 -0.2794)
			(end 0.12065 -0.2794)
			(stroke
				(width 0.1)
				(type default)
			)
			(layer "F.Fab")
		)
		(fp_line
			(start 0.12065 -0.2794)
			(end 0.12065 -0.3048)
			(stroke
				(width 0.1)
				(type default)
			)
			(layer "F.Fab")
		)
		(fp_line
			(start 0.12065 -0.3048)
			(end 0.67945 -0.3048)
			(stroke
				(width 0.1)
				(type default)
			)
			(layer "F.Fab")
		)
		(fp_line
			(start 0.67945 -0.3048)
			(end 0.67945 0.3048)
			(stroke
				(width 0.1)
				(type default)
			)
			(layer "F.Fab")
		)
		(fp_line
			(start -0.67945 -0.305054)
			(end -0.12065 -0.305054)
			(stroke
				(width 0.1)
				(type default)
			)
			(layer "F.Fab")
		)
		(fp_line
			(start -0.12065 -0.305054)
			(end -0.12065 -0.2794)
			(stroke
				(width 0.1)
				(type default)
			)
			(layer "F.Fab")
		)
		(pad "1" smd circle
			(at -0.40005 0 270)
			(size 0 0)
			(layers "F.Cu" "F.Mask" "F.Paste")
			(net "GPU_BASE_ID1")
		)
		(pad "2" smd circle
			(at 0.40005 0 270)
			(size 0 0)
			(layers "F.Cu" "F.Mask" "F.Paste")
			(net "GPU_BASE_ID1_R")
		)
	)
	(footprint ""
		(layer "F.Cu")
		(at 322.565268 -339.372448)
		(property "Reference" "PC86_2"
			(at 0 0 0)
			(layer "F.SilkS")
			(hide yes)
			(effects
				(font
					(size 1.27 1.27)
				)
			)
		)
		(property "Value" ""
			(at 0 0 0)
			(layer "F.Fab")
			(effects
				(font
					(size 1.27 1.27)
				)
			)
		)
		(duplicate_pad_numbers_are_jumpers no)
		(fp_line
			(start -0.7874 -0.4064)
			(end 0.7874 -0.4064)
			(stroke
				(width 0.1524)
				(type default)
			)
			(layer "F.SilkS")
		)
		(fp_line
			(start -0.7874 0.4064)
			(end -0.7874 -0.4064)
			(stroke
				(width 0.1524)
				(type default)
			)
			(layer "F.SilkS")
		)
		(fp_line
			(start 0.7874 -0.4064)
			(end 0.7874 0.4064)
			(stroke
				(width 0.1524)
				(type default)
			)
			(layer "F.SilkS")
		)
		(fp_line
			(start 0.7874 0.4064)
			(end -0.7874 0.4064)
			(stroke
				(width 0.1524)
				(type default)
			)
			(layer "F.SilkS")
		)
		(fp_line
			(start -0.67945 -0.305054)
			(end -0.12065 -0.305054)
			(stroke
				(width 0.1)
				(type default)
			)
			(layer "F.Fab")
		)
		(fp_line
			(start -0.67945 0.3048)
			(end -0.67945 -0.305054)
			(stroke
				(width 0.1)
				(type default)
			)
			(layer "F.Fab")
		)
		(fp_line
			(start -0.12065 -0.305054)
			(end -0.12065 -0.2794)
			(stroke
				(width 0.1)
				(type default)
			)
			(layer "F.Fab")
		)
		(fp_line
			(start -0.12065 -0.2794)
			(end 0.12065 -0.2794)
			(stroke
				(width 0.1)
				(type default)
			)
			(layer "F.Fab")
		)
		(fp_line
			(start -0.12065 0.2794)
			(end -0.12065 0.3048)
			(stroke
				(width 0.1)
				(type default)
			)
			(layer "F.Fab")
		)
		(fp_line
			(start -0.12065 0.3048)
			(end -0.67945 0.3048)
			(stroke
				(width 0.1)
				(type default)
			)
			(layer "F.Fab")
		)
		(fp_line
			(start 0.120396 0.2794)
			(end -0.12065 0.2794)
			(stroke
				(width 0.1)
				(type default)
			)
			(layer "F.Fab")
		)
		(fp_line
			(start 0.120396 0.3048)
			(end 0.120396 0.2794)
			(stroke
				(width 0.1)
				(type default)
			)
			(layer "F.Fab")
		)
		(fp_line
			(start 0.12065 -0.3048)
			(end 0.67945 -0.3048)
			(stroke
				(width 0.1)
				(type default)
			)
			(layer "F.Fab")
		)
		(fp_line
			(start 0.12065 -0.2794)
			(end 0.12065 -0.3048)
			(stroke
				(width 0.1)
				(type default)
			)
			(layer "F.Fab")
		)
		(fp_line
			(start 0.67945 -0.3048)
			(end 0.67945 0.3048)
			(stroke
				(width 0.1)
				(type default)
			)
			(layer "F.Fab")
		)
		(fp_line
			(start 0.67945 0.3048)
			(end 0.120396 0.3048)
			(stroke
				(width 0.1)
				(type default)
			)
			(layer "F.Fab")
		)
		(pad "1" smd circle
			(at -0.40005 0)
			(size 0 0)
			(layers "F.Cu" "F.Mask" "F.Paste")
			(net "SW_P12V_AUX_PVDDCR_CPU1_P0_FLT")
		)
		(pad "2" smd circle
			(at 0.40005 0)
			(size 0 0)
			(layers "F.Cu" "F.Mask" "F.Paste")
			(net "GND")
		)
	)
)
